(kicad_pcb
	(version 20260206)
	(generator "pcbnew")
	(generator_version "10.0")
	(general
		(thickness 1.6)
		(legacy_teardrops no)
	)
	(paper "A4")
	(title_block
		(title "03242023_DA0F0TMBIJ0_F0T_Motherboard_J_brd_V01_OCP.brd")
		(comment 1 "Grand Teton / footprints 729-734 of 6105")
	)
	(layers
		(0 "F.Cu" signal "TOP")
		(4 "In1.Cu" signal "GND")
		(6 "In2.Cu" signal "IN1")
		(8 "In3.Cu" signal "GND1")
		(10 "In4.Cu" signal "IN2")
		(12 "In5.Cu" signal "GND2")
		(14 "In6.Cu" signal "IN3")
		(16 "In7.Cu" signal "GND3")
		(18 "In8.Cu" signal "VCC")
		(20 "In9.Cu" signal "VCC1")
		(22 "In10.Cu" signal "GND4")
		(24 "In11.Cu" signal "IN4")
		(26 "In12.Cu" signal "GND5")
		(28 "In13.Cu" signal "IN5")
		(30 "In14.Cu" signal "GND6")
		(32 "In15.Cu" signal "IN6")
		(34 "In16.Cu" signal "GND7")
		(2 "B.Cu" signal "BOTTOM")
		(9 "F.Adhes" user "F.Adhesive")
		(11 "B.Adhes" user "B.Adhesive")
		(13 "F.Paste" user "Package Geometry/Pastemask Top")
		(15 "B.Paste" user "Package Geometry/Pastemask Bottom")
		(5 "F.SilkS" user "Ref Des/Silkscreen Top")
		(7 "B.SilkS" user "Ref Des/Silkscreen Bottom")
		(1 "F.Mask" user "Board Geometry/Soldermask Top")
		(3 "B.Mask" user "Board Geometry/Soldermask Bottom")
		(17 "Dwgs.User" user "User.Drawings")
		(19 "Cmts.User" user "User.Comments")
		(21 "Eco1.User" user "User.Eco1")
		(23 "Eco2.User" user "User.Eco2")
		(25 "Edge.Cuts" user "Board Geometry/Outline")
		(27 "Margin" user)
		(31 "F.CrtYd" user "Package Geometry/Place Bound Top")
		(29 "B.CrtYd" user "Package Geometry/Place Bound Bottom")
		(35 "F.Fab" user "Ref Des/Assembly Top")
		(33 "B.Fab" user "Ref Des/Assembly Bottom")
	)
	(footprint ""
		(layer "F.Cu")
		(at 31.29788 -424.271948)
		(property "Reference" "R3455"
			(at 0 0 0)
			(layer "F.SilkS")
			(hide yes)
			(effects
				(font
					(size 1.27 1.27)
				)
			)
		)
		(property "Value" ""
			(at 0 0 0)
			(layer "F.Fab")
			(effects
				(font
					(size 1.27 1.27)
				)
			)
		)
		(duplicate_pad_numbers_are_jumpers no)
		(fp_line
			(start -0.7874 -0.4064)
			(end 0.7874 -0.4064)
			(stroke
				(width 0.1524)
				(type default)
			)
			(layer "F.SilkS")
		)
		(fp_line
			(start -0.7874 0.4064)
			(end -0.7874 -0.4064)
			(stroke
				(width 0.1524)
				(type default)
			)
			(layer "F.SilkS")
		)
		(fp_line
			(start 0.7874 -0.4064)
			(end 0.7874 0.4064)
			(stroke
				(width 0.1524)
				(type default)
			)
			(layer "F.SilkS")
		)
		(fp_line
			(start 0.7874 0.4064)
			(end -0.7874 0.4064)
			(stroke
				(width 0.1524)
				(type default)
			)
			(layer "F.SilkS")
		)
		(fp_line
			(start -0.67945 -0.305054)
			(end -0.12065 -0.305054)
			(stroke
				(width 0.1)
				(type default)
			)
			(layer "F.Fab")
		)
		(fp_line
			(start -0.67945 0.3048)
			(end -0.67945 -0.305054)
			(stroke
				(width 0.1)
				(type default)
			)
			(layer "F.Fab")
		)
		(fp_line
			(start -0.12065 -0.305054)
			(end -0.12065 -0.2794)
			(stroke
				(width 0.1)
				(type default)
			)
			(layer "F.Fab")
		)
		(fp_line
			(start -0.12065 -0.2794)
			(end 0.12065 -0.2794)
			(stroke
				(width 0.1)
				(type default)
			)
			(layer "F.Fab")
		)
		(fp_line
			(start -0.12065 0.2794)
			(end -0.12065 0.3048)
			(stroke
				(width 0.1)
				(type default)
			)
			(layer "F.Fab")
		)
		(fp_line
			(start -0.12065 0.3048)
			(end -0.67945 0.3048)
			(stroke
				(width 0.1)
				(type default)
			)
			(layer "F.Fab")
		)
		(fp_line
			(start 0.120396 0.2794)
			(end -0.12065 0.2794)
			(stroke
				(width 0.1)
				(type default)
			)
			(layer "F.Fab")
		)
		(fp_line
			(start 0.120396 0.3048)
			(end 0.120396 0.2794)
			(stroke
				(width 0.1)
				(type default)
			)
			(layer "F.Fab")
		)
		(fp_line
			(start 0.12065 -0.3048)
			(end 0.67945 -0.3048)
			(stroke
				(width 0.1)
				(type default)
			)
			(layer "F.Fab")
		)
		(fp_line
			(start 0.12065 -0.2794)
			(end 0.12065 -0.3048)
			(stroke
				(width 0.1)
				(type default)
			)
			(layer "F.Fab")
		)
		(fp_line
			(start 0.67945 -0.3048)
			(end 0.67945 0.3048)
			(stroke
				(width 0.1)
				(type default)
			)
			(layer "F.Fab")
		)
		(fp_line
			(start 0.67945 0.3048)
			(end 0.120396 0.3048)
			(stroke
				(width 0.1)
				(type default)
			)
			(layer "F.Fab")
		)
		(pad "1" smd circle
			(at -0.40005 0)
			(size 0 0)
			(layers "F.Cu" "F.Mask" "F.Paste")
			(net "RST_PERST_1_SWB_BUF_R_N")
		)
		(pad "2" smd circle
			(at 0.40005 0)
			(size 0 0)
			(layers "F.Cu" "F.Mask" "F.Paste")
			(net "GND")
		)
	)
	(footprint ""
		(layer "F.Cu")
		(at 424.205654 -371.76837 90)
		(property "Reference" "PC1189"
			(at 0 0 90)
			(layer "F.SilkS")
			(hide yes)
			(effects
				(font
					(size 1.27 1.27)
				)
			)
		)
		(property "Value" ""
			(at 0 0 90)
			(layer "F.Fab")
			(effects
				(font
					(size 1.27 1.27)
				)
			)
		)
		(duplicate_pad_numbers_are_jumpers no)
		(fp_line
			(start -3.400044 1.249934)
			(end 3.400044 1.249934)
			(stroke
				(width 0.1524)
				(type default)
			)
			(layer "F.SilkS")
		)
		(fp_circle
			(center 0 1.249934)
			(end 0 4.649978)
			(stroke
				(width 0.1524)
				(type default)
			)
			(fill no)
			(layer "F.SilkS")
		)
		(fp_poly
			(pts
				(arc
					(start -3.400044 1.249934)
					(mid 0 4.649978)
					(end 3.400044 1.249934)
				)
			)
			(stroke
				(width 0)
				(type default)
			)
			(fill yes)
			(layer "F.SilkS")
		)
		(fp_circle
			(center 0 1.249934)
			(end 0 4.649978)
			(stroke
				(width 0.1)
				(type default)
			)
			(fill no)
			(layer "F.Fab")
		)
		(pad "1" thru_hole rect
			(at 0 0 90)
			(size 1.524 1.524)
			(drill 1.016)
			(layers "*.Cu" "*.Mask")
			(remove_unused_layers no)
			(net "SW_P12V_PVCCFA_EHV_FIVRA_CPU0_R")
			(clearance 0)
			(padstack
				(mode front_inner_back)
				(layer "Inner"
					(shape circle)
					(size 1.524 1.524)
					(clearance 0)
				)
				(layer "B.Cu"
					(shape rect)
					(size 1.524 1.524)
					(clearance 0)
				)
			)
		)
		(pad "2" thru_hole circle
			(at 0 2.500122 90)
			(size 1.524 1.524)
			(drill 1.016)
			(layers "*.Cu" "*.Mask")
			(remove_unused_layers no)
			(net "GND")
			(clearance 0)
		)
	)
	(footprint ""
		(layer "F.Cu")
		(at 68.010786 -65.082674 -90)
		(property "Reference" "R3085"
			(at 0 0 270)
			(layer "F.SilkS")
			(hide yes)
			(effects
				(font
					(size 1.27 1.27)
				)
			)
		)
		(property "Value" ""
			(at 0 0 270)
			(layer "F.Fab")
			(effects
				(font
					(size 1.27 1.27)
				)
			)
		)
		(duplicate_pad_numbers_are_jumpers no)
		(fp_line
			(start -0.7874 0.4064)
			(end -0.7874 -0.4064)
			(stroke
				(width 0.1524)
				(type default)
			)
			(layer "F.SilkS")
		)
		(fp_line
			(start 0.7874 0.4064)
			(end -0.7874 0.4064)
			(stroke
				(width 0.1524)
				(type default)
			)
			(layer "F.SilkS")
		)
		(fp_line
			(start -0.7874 -0.4064)
			(end 0.7874 -0.4064)
			(stroke
				(width 0.1524)
				(type default)
			)
			(layer "F.SilkS")
		)
		(fp_line
			(start 0.7874 -0.4064)
			(end 0.7874 0.4064)
			(stroke
				(width 0.1524)
				(type default)
			)
			(layer "F.SilkS")
		)
		(fp_line
			(start -0.67945 0.3048)
			(end -0.67945 -0.305054)
			(stroke
				(width 0.1)
				(type default)
			)
			(layer "F.Fab")
		)
		(fp_line
			(start -0.12065 0.3048)
			(end -0.67945 0.3048)
			(stroke
				(width 0.1)
				(type default)
			)
			(layer "F.Fab")
		)
		(fp_line
			(start 0.120396 0.3048)
			(end 0.120396 0.2794)
			(stroke
				(width 0.1)
				(type default)
			)
			(layer "F.Fab")
		)
		(fp_line
			(start 0.67945 0.3048)
			(end 0.120396 0.3048)
			(stroke
				(width 0.1)
				(type default)
			)
			(layer "F.Fab")
		)
		(fp_line
			(start -0.12065 0.2794)
			(end -0.12065 0.3048)
			(stroke
				(width 0.1)
				(type default)
			)
			(layer "F.Fab")
		)
		(fp_line
			(start 0.120396 0.2794)
			(end -0.12065 0.2794)
			(stroke
				(width 0.1)
				(type default)
			)
			(layer "F.Fab")
		)
		(fp_line
			(start -0.12065 -0.2794)
			(end 0.12065 -0.2794)
			(stroke
				(width 0.1)
				(type default)
			)
			(layer "F.Fab")
		)
		(fp_line
			(start 0.12065 -0.2794)
			(end 0.12065 -0.3048)
			(stroke
				(width 0.1)
				(type default)
			)
			(layer "F.Fab")
		)
		(fp_line
			(start 0.12065 -0.3048)
			(end 0.67945 -0.3048)
			(stroke
				(width 0.1)
				(type default)
			)
			(layer "F.Fab")
		)
		(fp_line
			(start 0.67945 -0.3048)
			(end 0.67945 0.3048)
			(stroke
				(width 0.1)
				(type default)
			)
			(layer "F.Fab")
		)
		(fp_line
			(start -0.67945 -0.305054)
			(end -0.12065 -0.305054)
			(stroke
				(width 0.1)
				(type default)
			)
			(layer "F.Fab")
		)
		(fp_line
			(start -0.12065 -0.305054)
			(end -0.12065 -0.2794)
			(stroke
				(width 0.1)
				(type default)
			)
			(layer "F.Fab")
		)
		(pad "1" smd circle
			(at -0.40005 0 270)
			(size 0 0)
			(layers "F.Cu" "F.Mask" "F.Paste")
			(net "LED_RST_PLD_CPU1_DRAM_GH_N")
		)
		(pad "2" smd circle
			(at 0.40005 0 270)
			(size 0 0)
			(layers "F.Cu" "F.Mask" "F.Paste")
			(net "P3V3_AUX")
		)
	)
	(footprint ""
		(layer "F.Cu")
		(at 172.8724 -93.538548 90)
		(property "Reference" "R4580"
			(at 0 0 90)
			(layer "F.SilkS")
			(hide yes)
			(effects
				(font
					(size 1.27 1.27)
				)
			)
		)
		(property "Value" ""
			(at 0 0 90)
			(layer "F.Fab")
			(effects
				(font
					(size 1.27 1.27)
				)
			)
		)
		(duplicate_pad_numbers_are_jumpers no)
		(fp_line
			(start 0.7874 -0.4064)
			(end 0.7874 0.4064)
			(stroke
				(width 0.1524)
				(type default)
			)
			(layer "F.SilkS")
		)
		(fp_line
			(start -0.7874 -0.4064)
			(end 0.7874 -0.4064)
			(stroke
				(width 0.1524)
				(type default)
			)
			(layer "F.SilkS")
		)
		(fp_line
			(start 0.7874 0.4064)
			(end -0.7874 0.4064)
			(stroke
				(width 0.1524)
				(type default)
			)
			(layer "F.SilkS")
		)
		(fp_line
			(start -0.7874 0.4064)
			(end -0.7874 -0.4064)
			(stroke
				(width 0.1524)
				(type default)
			)
			(layer "F.SilkS")
		)
		(fp_line
			(start -0.12065 -0.305054)
			(end -0.12065 -0.2794)
			(stroke
				(width 0.1)
				(type default)
			)
			(layer "F.Fab")
		)
		(fp_line
			(start -0.67945 -0.305054)
			(end -0.12065 -0.305054)
			(stroke
				(width 0.1)
				(type default)
			)
			(layer "F.Fab")
		)
		(fp_line
			(start 0.67945 -0.3048)
			(end 0.67945 0.3048)
			(stroke
				(width 0.1)
				(type default)
			)
			(layer "F.Fab")
		)
		(fp_line
			(start 0.12065 -0.3048)
			(end 0.67945 -0.3048)
			(stroke
				(width 0.1)
				(type default)
			)
			(layer "F.Fab")
		)
		(fp_line
			(start 0.12065 -0.2794)
			(end 0.12065 -0.3048)
			(stroke
				(width 0.1)
				(type default)
			)
			(layer "F.Fab")
		)
		(fp_line
			(start -0.12065 -0.2794)
			(end 0.12065 -0.2794)
			(stroke
				(width 0.1)
				(type default)
			)
			(layer "F.Fab")
		)
		(fp_line
			(start 0.120396 0.2794)
			(end -0.12065 0.2794)
			(stroke
				(width 0.1)
				(type default)
			)
			(layer "F.Fab")
		)
		(fp_line
			(start -0.12065 0.2794)
			(end -0.12065 0.3048)
			(stroke
				(width 0.1)
				(type default)
			)
			(layer "F.Fab")
		)
		(fp_line
			(start 0.67945 0.3048)
			(end 0.120396 0.3048)
			(stroke
				(width 0.1)
				(type default)
			)
			(layer "F.Fab")
		)
		(fp_line
			(start 0.120396 0.3048)
			(end 0.120396 0.2794)
			(stroke
				(width 0.1)
				(type default)
			)
			(layer "F.Fab")
		)
		(fp_line
			(start -0.12065 0.3048)
			(end -0.67945 0.3048)
			(stroke
				(width 0.1)
				(type default)
			)
			(layer "F.Fab")
		)
		(fp_line
			(start -0.67945 0.3048)
			(end -0.67945 -0.305054)
			(stroke
				(width 0.1)
				(type default)
			)
			(layer "F.Fab")
		)
		(pad "1" smd rect
			(at -0.40005 0 270)
			(size 0.4572 0.508)
			(layers "F.Cu" "F.Mask" "F.Paste")
			(net "P3V3_AUX")
		)
		(pad "2" smd rect
			(at 0.40005 0 270)
			(size 0.4572 0.508)
			(layers "F.Cu" "F.Mask" "F.Paste")
			(net "FM_BOARD_BMC_SKU_ID4")
		)
	)
	(footprint ""
		(layer "F.Cu")
		(at 367.63452 -65.771268)
		(property "Reference" "U18"
			(at -2.032 -3.27533 0)
			(unlocked yes)
			(layer "F.SilkS")
			(effects
				(font
					(size 0.7874 0.5842)
					(thickness 0.1524)
				)
				(justify left)
			)
		)
		(property "Value" ""
			(at 0 0 0)
			(layer "F.Fab")
			(effects
				(font
					(size 1.27 1.27)
				)
			)
		)
		(duplicate_pad_numbers_are_jumpers no)
		(fp_line
			(start -2.0066 -2.5527)
			(end -0.5715 -2.5527)
			(stroke
				(width 0.1524)
				(type default)
			)
			(layer "F.SilkS")
		)
		(fp_line
			(start -2.0066 2.5527)
			(end -2.0066 -2.5527)
			(stroke
				(width 0.1524)
				(type default)
			)
			(layer "F.SilkS")
		)
		(fp_line
			(start -0.5715 -2.5527)
			(end 0 -1.9812)
			(stroke
				(width 0.1524)
				(type default)
			)
			(layer "F.SilkS")
		)
		(fp_line
			(start 0 -1.9812)
			(end 0.5715 -2.5527)
			(stroke
				(width 0.1524)
				(type default)
			)
			(layer "F.SilkS")
		)
		(fp_line
			(start 0.5715 -2.5527)
			(end 2.0066 -2.5527)
			(stroke
				(width 0.1524)
				(type default)
			)
			(layer "F.SilkS")
		)
		(fp_line
			(start 2.0066 -2.5527)
			(end 2.0066 2.5527)
			(stroke
				(width 0.1524)
				(type default)
			)
			(layer "F.SilkS")
		)
		(fp_line
			(start 2.0066 2.5527)
			(end -2.0066 2.5527)
			(stroke
				(width 0.1524)
				(type default)
			)
			(layer "F.SilkS")
		)
		(fp_poly
			(pts
				(xy -4.36372 -2.233168) (xy -3.81 -1.905) (xy -4.36372 -1.608328)
			)
			(stroke
				(width 0)
				(type default)
			)
			(fill yes)
			(layer "F.SilkS")
		)
		(fp_line
			(start -2.249932 -2.549906)
			(end 2.249932 -2.549906)
			(stroke
				(width 0.1)
				(type default)
			)
			(layer "F.Fab")
		)
		(fp_line
			(start -2.249932 2.549906)
			(end -2.249932 -2.549906)
			(stroke
				(width 0.1)
				(type default)
			)
			(layer "F.Fab")
		)
		(fp_line
			(start 2.249932 -2.549906)
			(end 2.249932 2.549906)
			(stroke
				(width 0.1)
				(type default)
			)
			(layer "F.Fab")
		)
		(fp_line
			(start 2.249932 2.549906)
			(end -2.249932 2.549906)
			(stroke
				(width 0.1)
				(type default)
			)
			(layer "F.Fab")
		)
		(fp_poly
			(pts
				(xy -4.36372 -1.608328) (xy -4.36372 -2.233168) (xy -3.81 -1.905)
			)
			(stroke
				(width 0)
				(type default)
			)
			(fill yes)
			(layer "F.Fab")
		)
		(pad "1" smd rect
			(at -2.921 -1.949958 270)
			(size 0.3556 1.4986)
			(layers "F.Cu" "F.Mask" "F.Paste")
			(net "PWRGD_PVNN_MAIN_CPU0")
		)
		(pad "2" smd rect
			(at -2.921 -1.299972 270)
			(size 0.3556 1.4986)
			(layers "F.Cu" "F.Mask" "F.Paste")
			(net "JTAG_DBP_CPU_HOOK9_MBP3_GTL_N")
		)
		(pad "3" smd rect
			(at -2.921 -0.649986 270)
			(size 0.3556 1.4986)
			(layers "F.Cu" "F.Mask" "F.Paste")
			(net "DBP_CPU_HOOK9_MBP3_GTL_QS_N")
		)
		(pad "4" smd rect
			(at -2.921 0 270)
			(size 0.3556 1.4986)
			(layers "F.Cu" "F.Mask" "F.Paste")
			(net "PWRGD_PVNN_MAIN_CPU0")
		)
		(pad "5" smd rect
			(at -2.921 0.649986 270)
			(size 0.3556 1.4986)
			(layers "F.Cu" "F.Mask" "F.Paste")
			(net "JTAG_DBP_CPU_HOOK8_MBP2_GTL_N")
		)
		(pad "6" smd rect
			(at -2.921 1.299972 270)
			(size 0.3556 1.4986)
			(layers "F.Cu" "F.Mask" "F.Paste")
			(net "DBP_CPU_HOOK8_MBP2_GTL_QS_N")
		)
		(pad "7" smd rect
			(at -2.921 1.949958 270)
			(size 0.3556 1.4986)
			(layers "F.Cu" "F.Mask" "F.Paste")
			(net "GND")
		)
		(pad "8" smd rect
			(at 2.921 1.949958 270)
			(size 0.3556 1.4986)
			(layers "F.Cu" "F.Mask" "F.Paste")
			(net "H_CPU_PRDY_QS_GTL_N")
		)
		(pad "9" smd rect
			(at 2.921 1.299972 270)
			(size 0.3556 1.4986)
			(layers "F.Cu" "F.Mask" "F.Paste")
			(net "JTAG_DBP_PRDY_N")
		)
		(pad "10" smd rect
			(at 2.921 0.649986 270)
			(size 0.3556 1.4986)
			(layers "F.Cu" "F.Mask" "F.Paste")
			(net "PWRGD_PVNN_MAIN_CPU0")
		)
		(pad "11" smd rect
			(at 2.921 0 270)
			(size 0.3556 1.4986)
			(layers "F.Cu" "F.Mask" "F.Paste")
			(net "H_CPU_PREQ_QS_GTL_N")
		)
		(pad "12" smd rect
			(at 2.921 -0.649986 270)
			(size 0.3556 1.4986)
			(layers "F.Cu" "F.Mask" "F.Paste")
			(net "JTAG_DBP_PREQ_N")
		)
		(pad "13" smd rect
			(at 2.921 -1.299972 270)
			(size 0.3556 1.4986)
			(layers "F.Cu" "F.Mask" "F.Paste")
			(net "PWRGD_PVNN_MAIN_CPU0")
		)
		(pad "14" smd rect
			(at 2.921 -1.949958 270)
			(size 0.3556 1.4986)
			(layers "F.Cu" "F.Mask" "F.Paste")
			(net "P3V3_AUX")
		)
	)
	(footprint ""
		(layer "F.Cu")
		(at 28.961334 -169.000678 90)
		(property "Reference" "PC1289"
			(at 0 0 90)
			(layer "F.SilkS")
			(hide yes)
			(effects
				(font
					(size 1.27 1.27)
				)
			)
		)
		(property "Value" ""
			(at 0 0 90)
			(layer "F.Fab")
			(effects
				(font
					(size 1.27 1.27)
				)
			)
		)
		(duplicate_pad_numbers_are_jumpers no)
		(fp_line
			(start 0.7874 -0.4064)
			(end 0.7874 0.4064)
			(stroke
				(width 0.1524)
				(type default)
			)
			(layer "F.SilkS")
		)
		(fp_line
			(start -0.7874 -0.4064)
			(end 0.7874 -0.4064)
			(stroke
				(width 0.1524)
				(type default)
			)
			(layer "F.SilkS")
		)
		(fp_line
			(start 0.7874 0.4064)
			(end -0.7874 0.4064)
			(stroke
				(width 0.1524)
				(type default)
			)
			(layer "F.SilkS")
		)
		(fp_line
			(start -0.7874 0.4064)
			(end -0.7874 -0.4064)
			(stroke
				(width 0.1524)
				(type default)
			)
			(layer "F.SilkS")
		)
		(fp_line
			(start -0.12065 -0.305054)
			(end -0.12065 -0.2794)
			(stroke
				(width 0.1)
				(type default)
			)
			(layer "F.Fab")
		)
		(fp_line
			(start -0.67945 -0.305054)
			(end -0.12065 -0.305054)
			(stroke
				(width 0.1)
				(type default)
			)
			(layer "F.Fab")
		)
		(fp_line
			(start 0.67945 -0.3048)
			(end 0.67945 0.3048)
			(stroke
				(width 0.1)
				(type default)
			)
			(layer "F.Fab")
		)
		(fp_line
			(start 0.12065 -0.3048)
			(end 0.67945 -0.3048)
			(stroke
				(width 0.1)
				(type default)
			)
			(layer "F.Fab")
		)
		(fp_line
			(start 0.12065 -0.2794)
			(end 0.12065 -0.3048)
			(stroke
				(width 0.1)
				(type default)
			)
			(layer "F.Fab")
		)
		(fp_line
			(start -0.12065 -0.2794)
			(end 0.12065 -0.2794)
			(stroke
				(width 0.1)
				(type default)
			)
			(layer "F.Fab")
		)
		(fp_line
			(start 0.120396 0.2794)
			(end -0.12065 0.2794)
			(stroke
				(width 0.1)
				(type default)
			)
			(layer "F.Fab")
		)
		(fp_line
			(start -0.12065 0.2794)
			(end -0.12065 0.3048)
			(stroke
				(width 0.1)
				(type default)
			)
			(layer "F.Fab")
		)
		(fp_line
			(start 0.67945 0.3048)
			(end 0.120396 0.3048)
			(stroke
				(width 0.1)
				(type default)
			)
			(layer "F.Fab")
		)
		(fp_line
			(start 0.120396 0.3048)
			(end 0.120396 0.2794)
			(stroke
				(width 0.1)
				(type default)
			)
			(layer "F.Fab")
		)
		(fp_line
			(start -0.12065 0.3048)
			(end -0.67945 0.3048)
			(stroke
				(width 0.1)
				(type default)
			)
			(layer "F.Fab")
		)
		(fp_line
			(start -0.67945 0.3048)
			(end -0.67945 -0.305054)
			(stroke
				(width 0.1)
				(type default)
			)
			(layer "F.Fab")
		)
		(pad "1" smd circle
			(at -0.40005 0 90)
			(size 0 0)
			(layers "F.Cu" "F.Mask" "F.Paste")
			(net "PVCCD_HV_CPU1_VREF")
		)
		(pad "2" smd circle
			(at 0.40005 0 90)
			(size 0 0)
			(layers "F.Cu" "F.Mask" "F.Paste")
			(net "GND")
		)
	)
)
